(kicad_pcb
	(version 20221018)
	(generator pcbnew)
	(general
    (thickness 1.7403)
  )
	(paper "A4")
	(title_block
    (title "Data Center RDIMM DDR4 Tester")
    (date "2024-09-30")
    (rev "1.2.4")
		(comment 9 "footprints 233-241 of 690")
	)
	(layers
    (0 "F.Cu" signal)
    (1 "In1.Cu" power)
    (2 "In2.Cu" signal)
    (3 "In3.Cu" power)
    (4 "In4.Cu" power)
    (5 "In5.Cu" signal)
    (6 "In6.Cu" power)
    (7 "In7.Cu" signal)
    (8 "In8.Cu" power)
    (9 "In9.Cu" signal)
    (10 "In10.Cu" power)
    (31 "B.Cu" signal)
    (32 "B.Adhes" user "B.Adhesive")
    (33 "F.Adhes" user "F.Adhesive")
    (34 "B.Paste" user)
    (35 "F.Paste" user)
    (36 "B.SilkS" user "B.Silkscreen")
    (37 "F.SilkS" user "F.Silkscreen")
    (38 "B.Mask" user)
    (39 "F.Mask" user)
    (40 "Dwgs.User" user "User.Drawings")
    (41 "Cmts.User" user "User.Comments")
    (42 "Eco1.User" user "User.Eco1")
    (43 "Eco2.User" user "User.Eco2")
    (44 "Edge.Cuts" user)
    (45 "Margin" user)
    (46 "B.CrtYd" user "B.Courtyard")
    (47 "F.CrtYd" user "F.Courtyard")
    (48 "B.Fab" user)
    (49 "F.Fab" user)
  )
	(footprint "data-center-rdimm-ddr4-tester-footprints:R_0402_1005Metric" (layer "F.Cu")
    (at 132.536328 96.110008 180)
    (descr "Resistor SMD 0402")
    (tags "resistor SMD 0402")
    (property "Author" "Antmicro")
    (property "License" "Apache-2.0")
    (property "MPN" "CR0402-FX-1002GLF")
    (property "Manufacturer" "Bourns")
    (property "Sheetfile" "supply.kicad_sch")
    (property "Sheetname" "Supply")
    (property "Tolerance" "1%")
    (property "Val" "10k")
    (property "ki_description" "10k resistor in 0402 package with 1% tolerance")
    (attr smd)
    (fp_text reference "R84" (at -0.663672 -0.389992 180) (layer "F.SilkS")
        (effects (font (size 0.7 0.7) (thickness 0.15)) (justify left bottom))
    )
    (fp_text value "R_10k_0402" (at 0 1.4 180) (layer "F.Fab") hide
        (effects (font (size 0.7 0.7) (thickness 0.15)) (justify left bottom))
    )
    (fp_text user "${REFERENCE}" (at -0.95 3.168 180) (layer "F.Fab") hide
        (effects (font (size 0.7 0.7) (thickness 0.15)) (justify left bottom))
    )
    (fp_text user "License: Apache-2.0" (at -0.95 5.169 180) (layer "F.Fab") hide
        (effects (font (size 0.7 0.7) (thickness 0.15)) (justify left bottom))
    )
    (fp_text user "Author: Antmicro" (at -0.95 4.169 180) (layer "F.Fab") hide
        (effects (font (size 0.7 0.7) (thickness 0.15)) (justify left bottom))
    )
    (fp_rect (start -0.93 -0.47) (end 0.93 0.47)
      (stroke (width 0.05) (type solid)) (fill none) (layer "F.CrtYd"))
    (fp_rect (start -0.5 -0.25) (end 0.5 0.25)
      (stroke (width 0.15) (type solid)) (fill none) (layer "F.Fab"))
    (pad "1" smd roundrect (at -0.485 0 180) (size 0.59 0.64) (layers "F.Cu" "F.Paste" "F.Mask") (roundrect_rratio 0.25)
      (net 653 "Net-(U12-FB)") (pintype "passive"))
    (pad "2" smd roundrect (at 0.485 0 180) (size 0.59 0.64) (layers "F.Cu" "F.Paste" "F.Mask") (roundrect_rratio 0.25)
      (net 9 "GND") (pintype "passive"))
  )
	(footprint "data-center-rdimm-ddr4-tester-footprints:AP62301WU-7-TSOT23-6" (layer "F.Cu")
    (at 138.336328 89.110008 -90)
    (property "Author" "Antmicro")
    (property "License" "Apache-2.0")
    (property "MPN" "AP62301WU-7")
    (property "Manufacturer" "Diodes Incorporated")
    (property "Sheetfile" "supply.kicad_sch")
    (property "Sheetname" "Supply")
    (attr smd)
    (fp_text reference "U4" (at -1.490008 2.236328) (layer "F.SilkS")
        (effects (font (size 0.7 0.7) (thickness 0.15)) (justify left bottom))
    )
    (fp_text value "AP62301WU-7" (at -0.005 2.6 -90) (layer "F.Fab") hide
        (effects (font (size 0.7 0.7) (thickness 0.15)) (justify left bottom))
    )
    (fp_text user "Author: Antmicro" (at -1.893 7.368 -90) (layer "F.Fab") hide
        (effects (font (size 0.7 0.7) (thickness 0.15)) (justify left bottom))
    )
    (fp_text user "License: Apache-2.0" (at -1.893 4.967 -90) (layer "F.Fab") hide
        (effects (font (size 0.7 0.7) (thickness 0.15)) (justify left bottom))
    )
    (fp_text user "${REFERENCE}" (at -1.893 6.168 -90) (layer "F.Fab") hide
        (effects (font (size 0.7 0.7) (thickness 0.15)) (justify left bottom))
    )
    (fp_line (start -1.4805 0.725) (end -1.4795 -0.725)
      (stroke (width 0.15) (type solid)) (layer "F.SilkS"))
    (fp_line (start -1.4805 0.725) (end -1.3905 0.725)
      (stroke (width 0.15) (type solid)) (layer "F.SilkS"))
    (fp_line (start -1.4795 -0.725) (end -1.3905 -0.725)
      (stroke (width 0.15) (type solid)) (layer "F.SilkS"))
    (fp_line (start 1.479 0.73) (end 1.38 0.73)
      (stroke (width 0.15) (type solid)) (layer "F.SilkS"))
    (fp_line (start 1.48 -0.72) (end 1.38 -0.72)
      (stroke (width 0.15) (type solid)) (layer "F.SilkS"))
    (fp_line (start 1.48 -0.72) (end 1.479 0.73)
      (stroke (width 0.15) (type solid)) (layer "F.SilkS"))
    (fp_circle (center -1.499 1.236) (end -1.45 1.236)
      (stroke (width 0.15) (type solid)) (fill solid) (layer "F.SilkS"))
    (fp_rect (start -1.65 -1.61) (end 1.65 1.61)
      (stroke (width 0.05) (type solid)) (fill none) (layer "F.CrtYd"))
    (fp_line (start -1.527 -0.833) (end 1.523 -0.833)
      (stroke (width 0.15) (type solid)) (layer "F.Fab"))
    (fp_line (start -1.527 0.491) (end -1.527 -0.833)
      (stroke (width 0.15) (type solid)) (layer "F.Fab"))
    (fp_line (start -1.527 0.491) (end -1.102 0.916)
      (stroke (width 0.15) (type solid)) (layer "F.Fab"))
    (fp_line (start -1.102 0.916) (end 1.523 0.916)
      (stroke (width 0.15) (type solid)) (layer "F.Fab"))
    (fp_line (start 1.523 -0.833) (end 1.523 0.916)
      (stroke (width 0.15) (type solid)) (layer "F.Fab"))
    (pad "1" smd rect (at -0.952 1.18 270) (size 0.7 0.8) (layers "F.Cu" "F.Paste" "F.Mask")
      (net 9 "GND") (pinfunction "GND") (pintype "power_in"))
    (pad "2" smd rect (at -0.001 1.18 270) (size 0.7 0.8) (layers "F.Cu" "F.Paste" "F.Mask")
      (net 3 "Net-(U4-SW)") (pinfunction "SW") (pintype "power_out"))
    (pad "3" smd rect (at 0.947 1.18 270) (size 0.7 0.8) (layers "F.Cu" "F.Paste" "F.Mask")
      (net 307 "5V0_SYS") (pinfunction "VIN") (pintype "power_in"))
    (pad "4" smd rect (at 0.947 -1.18 270) (size 0.7 0.8) (layers "F.Cu" "F.Paste" "F.Mask")
      (net 614 "Net-(U4-FB)") (pinfunction "FB") (pintype "input"))
    (pad "5" smd rect (at -0.001 -1.18 270) (size 0.7 0.8) (layers "F.Cu" "F.Paste" "F.Mask")
      (net 603 "Net-(U4-EN)") (pinfunction "EN") (pintype "input"))
    (pad "6" smd rect (at -0.952 -1.18 270) (size 0.7 0.8) (layers "F.Cu" "F.Paste" "F.Mask")
      (net 2 "Net-(U4-BST)") (pinfunction "BST") (pintype "output"))
  )
	(footprint "data-center-rdimm-ddr4-tester-footprints:C_0402_1005Metric" (layer "F.Cu")
    (at 148.499328 121.852008 -90)
    (descr "Capacitor SMD 0402")
    (tags "capacitor SMD 0402")
    (property "Author" "Antmicro")
    (property "Dielectric" "")
    (property "License" "Apache-2.0")
    (property "MPN" "C1005X6S1A105K050BC")
    (property "Manufacturer" "TDK")
    (property "Sheetfile" "supply.kicad_sch")
    (property "Sheetname" "Supply")
    (property "Val" "1u")
    (property "Voltage" "")
    (property "ki_description" " ")
    (attr smd)
    (fp_text reference "C156" (at 1.477992 2.539328 -90) (layer "F.SilkS")
        (effects (font (size 0.7 0.7) (thickness 0.15)) (justify left bottom))
    )
    (fp_text value "C_1u_0402" (at 0 1.4 -90) (layer "F.Fab") hide
        (effects (font (size 0.7 0.7) (thickness 0.15)) (justify left bottom))
    )
    (fp_text user "Author: Antmicro" (at -0.932 4.17 -90) (layer "F.Fab") hide
        (effects (font (size 0.7 0.7) (thickness 0.15)) (justify left bottom))
    )
    (fp_text user "${REFERENCE}" (at -0.932 3.168 -90) (layer "F.Fab") hide
        (effects (font (size 0.7 0.7) (thickness 0.15)) (justify left bottom))
    )
    (fp_text user "License: Apache-2.0" (at -0.932 5.17 -90) (layer "F.Fab") hide
        (effects (font (size 0.7 0.7) (thickness 0.15)) (justify left bottom))
    )
    (fp_rect (start -0.94 -0.47) (end 0.94 0.47)
      (stroke (width 0.05) (type solid)) (fill none) (layer "F.CrtYd"))
    (fp_rect (start -0.499 -0.249) (end 0.499 0.249)
      (stroke (width 0.15) (type solid)) (fill none) (layer "F.Fab"))
    (pad "1" smd roundrect (at -0.484 0 270) (size 0.59 0.64) (layers "F.Cu" "F.Paste" "F.Mask") (roundrect_rratio 0.25)
      (net 176 "VCC1V2") (pintype "passive"))
    (pad "2" smd roundrect (at 0.484 0 270) (size 0.59 0.64) (layers "F.Cu" "F.Paste" "F.Mask") (roundrect_rratio 0.25)
      (net 9 "GND") (pintype "passive"))
  )
	(footprint "data-center-rdimm-ddr4-tester-footprints:C_0402_1005Metric" (layer "F.Cu")
    (at 142.036328 81.810008)
    (descr "Capacitor SMD 0402")
    (tags "capacitor SMD 0402")
    (property "Author" "Antmicro")
    (property "Dielectric" "")
    (property "License" "Apache-2.0")
    (property "MPN" "04024W226MAT2A")
    (property "Manufacturer" "AVX")
    (property "Sheetfile" "supply.kicad_sch")
    (property "Sheetname" "Supply")
    (property "Val" "22u")
    (property "Voltage" "")
    (property "ki_description" " ")
    (attr smd)
    (fp_text reference "C96" (at 0.793672 0.369992) (layer "F.SilkS")
        (effects (font (size 0.7 0.7) (thickness 0.15)) (justify left bottom))
    )
    (fp_text value "C_22u_0402" (at 0 1.4) (layer "F.Fab") hide
        (effects (font (size 0.7 0.7) (thickness 0.15)) (justify left bottom))
    )
    (fp_text user "${REFERENCE}" (at -0.932 3.168) (layer "F.Fab") hide
        (effects (font (size 0.7 0.7) (thickness 0.15)) (justify left bottom))
    )
    (fp_text user "License: Apache-2.0" (at -0.932 5.17) (layer "F.Fab") hide
        (effects (font (size 0.7 0.7) (thickness 0.15)) (justify left bottom))
    )
    (fp_text user "Author: Antmicro" (at -0.932 4.17) (layer "F.Fab") hide
        (effects (font (size 0.7 0.7) (thickness 0.15)) (justify left bottom))
    )
    (fp_rect (start -0.94 -0.47) (end 0.94 0.47)
      (stroke (width 0.05) (type solid)) (fill none) (layer "F.CrtYd"))
    (fp_rect (start -0.499 -0.249) (end 0.499 0.249)
      (stroke (width 0.15) (type solid)) (fill none) (layer "F.Fab"))
    (pad "1" smd roundrect (at -0.484 0) (size 0.59 0.64) (layers "F.Cu" "F.Paste" "F.Mask") (roundrect_rratio 0.25)
      (net 300 "VCC1V0") (pintype "passive"))
    (pad "2" smd roundrect (at 0.484 0) (size 0.59 0.64) (layers "F.Cu" "F.Paste" "F.Mask") (roundrect_rratio 0.25)
      (net 9 "GND") (pintype "passive"))
  )
	(footprint "data-center-rdimm-ddr4-tester-footprints:R_1206_3216Metric" (layer "F.Cu")
    (at 130.7 83.4 90)
    (property "Author" "Antmicro")
    (property "License" "Apache-2.0")
    (property "MPN" "RL1206FR-7W0R01L")
    (property "Manufacturer" "Yaego")
    (property "Sheetfile" "supply.kicad_sch")
    (property "Sheetname" "Supply")
    (property "Tolerance" "1%")
    (property "Val" "0R01")
    (property "ki_description" "0R01 resistor in 1206 package with unspecified tolerance")
    (attr smd)
    (fp_text reference "R203" (at -1.39 -1.12 90) (layer "F.SilkS")
        (effects (font (size 0.7 0.7) (thickness 0.15)) (justify left bottom))
    )
    (fp_text value "R_0R01_1206" (at 0 2 90) (layer "F.Fab") hide
        (effects (font (size 0.7 0.7) (thickness 0.15)) (justify left bottom))
    )
    (fp_text user "Author: Antmicro" (at -2.401 4.899 90) (layer "F.Fab") hide
        (effects (font (size 0.7 0.7) (thickness 0.15)) (justify left bottom))
    )
    (fp_text user "License: Apache-2.0" (at -2.401 6.3 90) (layer "F.Fab") hide
        (effects (font (size 0.7 0.7) (thickness 0.15)) (justify left bottom))
    )
    (fp_text user "${REFERENCE}" (at -2.401 3.5 90) (layer "F.Fab") hide
        (effects (font (size 0.7 0.7) (thickness 0.15)) (justify left bottom))
    )
    (fp_line (start 0 -0.902) (end -0.5 -0.902)
      (stroke (width 0.15) (type solid)) (layer "F.SilkS"))
    (fp_line (start 0 -0.902) (end 0.498 -0.902)
      (stroke (width 0.15) (type solid)) (layer "F.SilkS"))
    (fp_line (start 0 0.9) (end -0.5 0.9)
      (stroke (width 0.15) (type solid)) (layer "F.SilkS"))
    (fp_line (start 0 0.9) (end 0.498 0.9)
      (stroke (width 0.15) (type solid)) (layer "F.SilkS"))
    (fp_rect (start -2.25 -1.05) (end 2.25 1.05)
      (stroke (width 0.05) (type solid)) (fill none) (layer "F.CrtYd"))
    (fp_line (start -1.601 -0.802) (end -1.601 0.8)
      (stroke (width 0.15) (type solid)) (layer "F.Fab"))
    (fp_line (start -1.601 -0.802) (end 1.6 -0.802)
      (stroke (width 0.15) (type solid)) (layer "F.Fab"))
    (fp_line (start -1.601 0.8) (end 1.6 0.8)
      (stroke (width 0.15) (type solid)) (layer "F.Fab"))
    (fp_line (start 1.6 -0.802) (end 1.6 0.8)
      (stroke (width 0.15) (type solid)) (layer "F.Fab"))
    (pad "1" smd roundrect (at -1.5 0 90) (size 1.2 1.8) (layers "F.Cu" "F.Paste" "F.Mask") (roundrect_rratio 0.15)
      (net 302 "VCC1V8") (pintype "passive"))
    (pad "2" smd roundrect (at 1.499 0 90) (size 1.2 1.8) (layers "F.Cu" "F.Paste" "F.Mask") (roundrect_rratio 0.15)
      (net 144 "1V8_SYS") (pintype "passive"))
  )
	(footprint "data-center-rdimm-ddr4-tester-footprints:R_0402_1005Metric" (layer "F.Cu")
    (at 223.8 122.8 90)
    (descr "Resistor SMD 0402")
    (tags "resistor SMD 0402")
    (property "Author" "Antmicro")
    (property "License" "Apache-2.0")
    (property "MPN" "CR0402-FX-1003GLF")
    (property "Manufacturer" "Bourns")
    (property "Sheetfile" "supply.kicad_sch")
    (property "Sheetname" "Supply")
    (property "Tolerance" "1%")
    (property "Val" "100k")
    (property "ki_description" "100k resistor in 0402 package with 1% tolerance")
    (attr smd)
    (fp_text reference "R121" (at -3.55 0.35 270) (layer "F.SilkS")
        (effects (font (size 0.7 0.7) (thickness 0.15)) (justify left bottom))
    )
    (fp_text value "R_100k_0402" (at 0 1.4 90) (layer "F.Fab") hide
        (effects (font (size 0.7 0.7) (thickness 0.15)) (justify left bottom))
    )
    (fp_text user "License: Apache-2.0" (at -0.95 5.169 90) (layer "F.Fab") hide
        (effects (font (size 0.7 0.7) (thickness 0.15)) (justify left bottom))
    )
    (fp_text user "Author: Antmicro" (at -0.95 4.169 90) (layer "F.Fab") hide
        (effects (font (size 0.7 0.7) (thickness 0.15)) (justify left bottom))
    )
    (fp_text user "${REFERENCE}" (at -0.95 3.168 90) (layer "F.Fab") hide
        (effects (font (size 0.7 0.7) (thickness 0.15)) (justify left bottom))
    )
    (fp_rect (start -0.93 -0.47) (end 0.93 0.47)
      (stroke (width 0.05) (type solid)) (fill none) (layer "F.CrtYd"))
    (fp_rect (start -0.5 -0.25) (end 0.5 0.25)
      (stroke (width 0.15) (type solid)) (fill none) (layer "F.Fab"))
    (pad "1" smd roundrect (at -0.485 0 90) (size 0.59 0.64) (layers "F.Cu" "F.Paste" "F.Mask") (roundrect_rratio 0.25)
      (net 584 "Net-(Q12-G)") (pintype "passive"))
    (pad "2" smd roundrect (at 0.485 0 90) (size 0.59 0.64) (layers "F.Cu" "F.Paste" "F.Mask") (roundrect_rratio 0.25)
      (net 9 "GND") (pintype "passive"))
  )
	(footprint "data-center-rdimm-ddr4-tester-footprints:C_0402_1005Metric" (layer "F.Cu")
    (at 123.275 99.525 -90)
    (descr "Capacitor SMD 0402")
    (tags "capacitor SMD 0402")
    (property "Author" "Antmicro")
    (property "Dielectric" "")
    (property "License" "Apache-2.0")
    (property "MPN" "CC0402MRX5R5BB106")
    (property "Manufacturer" "Yaego")
    (property "Sheetfile" "supply.kicad_sch")
    (property "Sheetname" "Supply")
    (property "Val" "10u")
    (property "Voltage" "")
    (property "ki_description" " ")
    (attr smd)
    (fp_text reference "C1" (at 2.265 -0.395 -90) (layer "F.SilkS")
        (effects (font (size 0.7 0.7) (thickness 0.15)) (justify left bottom))
    )
    (fp_text value "C_10u_0402" (at 0 1.4 -90) (layer "F.Fab") hide
        (effects (font (size 0.7 0.7) (thickness 0.15)) (justify left bottom))
    )
    (fp_text user "License: Apache-2.0" (at -0.932 5.17 -90) (layer "F.Fab") hide
        (effects (font (size 0.7 0.7) (thickness 0.15)) (justify left bottom))
    )
    (fp_text user "Author: Antmicro" (at -0.932 4.17 -90) (layer "F.Fab") hide
        (effects (font (size 0.7 0.7) (thickness 0.15)) (justify left bottom))
    )
    (fp_text user "${REFERENCE}" (at -0.932 3.168 -90) (layer "F.Fab") hide
        (effects (font (size 0.7 0.7) (thickness 0.15)) (justify left bottom))
    )
    (fp_rect (start -0.94 -0.47) (end 0.94 0.47)
      (stroke (width 0.05) (type solid)) (fill none) (layer "F.CrtYd"))
    (fp_rect (start -0.499 -0.249) (end 0.499 0.249)
      (stroke (width 0.15) (type solid)) (fill none) (layer "F.Fab"))
    (pad "1" smd roundrect (at -0.484 0 270) (size 0.59 0.64) (layers "F.Cu" "F.Paste" "F.Mask") (roundrect_rratio 0.25)
      (net 307 "5V0_SYS") (pintype "passive"))
    (pad "2" smd roundrect (at 0.484 0 270) (size 0.59 0.64) (layers "F.Cu" "F.Paste" "F.Mask") (roundrect_rratio 0.25)
      (net 9 "GND") (pintype "passive"))
  )
	(footprint "data-center-rdimm-ddr4-tester-footprints:R_0201" (layer "F.Cu")
    (at 163.28 109.02 -90)
    (descr "Resistor SMD 0201")
    (tags "resistor SMD 0201")
    (property "Author" "Antmicro")
    (property "License" "Apache-2.0")
    (property "MPN" "CR0201-FX-0R00GLF")
    (property "Manufacturer" "Bourns")
    (property "Sheetfile" "ethernet.kicad_sch")
    (property "Sheetname" "Ethernet")
    (property "Tolerance" "1%")
    (property "Val" "0R")
    (property "ki_description" "0R resistor in 0201 package with 1% tolerance")
    (attr smd)
    (fp_text reference "R111" (at 3.43 -0.31 -90) (layer "F.SilkS")
        (effects (font (size 0.7 0.7) (thickness 0.15)) (justify left bottom))
    )
    (fp_text value "R_0R_0201" (at 0 1.25 -90) (layer "F.Fab") hide
        (effects (font (size 0.7 0.7) (thickness 0.15)) (justify left bottom))
    )
    (fp_text user "${REFERENCE}" (at -0.71 3.25 -90) (layer "F.Fab") hide
        (effects (font (size 0.7 0.7) (thickness 0.15)) (justify left bottom))
    )
    (fp_text user "Author: Antmicro" (at -0.71 5.25 -90) (layer "F.Fab") hide
        (effects (font (size 0.7 0.7) (thickness 0.15)) (justify left bottom))
    )
    (fp_text user "License: Apache-2.0" (at -0.71 4.25 -90) (layer "F.Fab") hide
        (effects (font (size 0.7 0.7) (thickness 0.15)) (justify left bottom))
    )
    (fp_rect (start -0.71 -0.36) (end 0.71 0.36)
      (stroke (width 0.05) (type solid)) (fill none) (layer "F.CrtYd"))
    (fp_rect (start -0.3 -0.15) (end 0.298 0.148)
      (stroke (width 0.15) (type solid)) (fill none) (layer "F.Fab"))
    (pad "" smd roundrect (at -0.346 0 270) (size 0.318 0.36) (layers "F.Paste") (roundrect_rratio 0.25))
    (pad "" smd roundrect (at 0.344 0 270) (size 0.318 0.36) (layers "F.Paste") (roundrect_rratio 0.25))
    (pad "1" smd roundrect (at -0.32 0 270) (size 0.46 0.4) (layers "F.Cu" "F.Mask") (roundrect_rratio 0.25)
      (net 830 "/Ethernet/ETH4_BP_P") (pintype "passive"))
    (pad "2" smd roundrect (at 0.32 0 270) (size 0.46 0.4) (layers "F.Cu" "F.Mask") (roundrect_rratio 0.25)
      (net 548 "/Ethernet/INT_ETH4_P") (pintype "passive"))
  )
	(footprint "data-center-rdimm-ddr4-tester-footprints:C_0402_1005Metric" (layer "F.Cu")
    (at 248.555 120.81 180)
    (descr "Capacitor SMD 0402")
    (tags "capacitor SMD 0402")
    (property "Author" "Antmicro")
    (property "Dielectric" "X5R")
    (property "License" "Apache-2.0")
    (property "MPN" "GRM155R61H104KE14D")
    (property "Manufacturer" "Murata")
    (property "Sheetfile" "pcie.kicad_sch")
    (property "Sheetname" "FPGA banks 115-116")
    (property "Val" "100n")
    (property "Voltage" "50V")
    (property "ki_description" " ")
    (attr smd)
    (fp_text reference "C246" (at 1.485 1.56 180) (layer "F.SilkS")
        (effects (font (size 0.7 0.7) (thickness 0.15)) (justify left bottom))
    )
    (fp_text value "C_100n_0402" (at 0 1.4 180) (layer "F.Fab") hide
        (effects (font (size 0.7 0.7) (thickness 0.15)) (justify left bottom))
    )
    (fp_text user "${REFERENCE}" (at -0.932 3.168 180) (layer "F.Fab") hide
        (effects (font (size 0.7 0.7) (thickness 0.15)) (justify left bottom))
    )
    (fp_text user "License: Apache-2.0" (at -0.932 5.17 180) (layer "F.Fab") hide
        (effects (font (size 0.7 0.7) (thickness 0.15)) (justify left bottom))
    )
    (fp_text user "Author: Antmicro" (at -0.932 4.17 180) (layer "F.Fab") hide
        (effects (font (size 0.7 0.7) (thickness 0.15)) (justify left bottom))
    )
    (fp_rect (start -0.94 -0.47) (end 0.94 0.47)
      (stroke (width 0.05) (type solid)) (fill none) (layer "F.CrtYd"))
    (fp_rect (start -0.499 -0.249) (end 0.499 0.249)
      (stroke (width 0.15) (type solid)) (fill none) (layer "F.Fab"))
    (pad "1" smd roundrect (at -0.484 0 180) (size 0.59 0.64) (layers "F.Cu" "F.Paste" "F.Mask") (roundrect_rratio 0.25)
      (net 403 "GTR_REFCLK0_C_P") (pintype "passive"))
    (pad "2" smd roundrect (at 0.484 0 180) (size 0.59 0.64) (layers "F.Cu" "F.Paste" "F.Mask") (roundrect_rratio 0.25)
      (net 404 "/FPGA banks 115-116/GTR_REFCLK0_P") (pintype "passive"))
  )
)
